#ISCELL
  mstr_misc dns *
  *
#ISCELL
  pure_quanta quanta_title_block_c *
  *
#ISCELL
  pure_quanta_power vcc15 *
  page476_i1
#CELL
  pure_quanta q_inductor *
  page476_i182
#CELL
  pure_quanta q_res *
  page476_i183
#ISCELL
  pure_quanta_power universal_power *
  page476_i184
#CELL
  pure_quanta q_res *
  page476_i185
#ISCELL
  pure_quanta_power universal_power *
  page476_i186
#CELL
  pure_quanta q_res *
  page476_i187
#ISCELL
  pure_quanta_power universal_gnd *
  page476_i188
#ISCELL
  pure_quanta_power universal_gnd *
  page476_i189
#ISCELL
  pure_quanta_power universal_gnd *
  page476_i190
#ISCELL
  pure_quanta_power universal_gnd *
  page476_i191
#ISCELL
  pure_quanta_power universal_gnd *
  page476_i192
#ISCELL
  pure_quanta_power universal_gnd *
  page476_i193
#ISCELL
  pure_quanta_power universal_gnd *
  page476_i194
#ISCELL
  pure_quanta_power universal_gnd *
  page476_i195
#ISCELL
  pure_quanta_power universal_gnd *
  page476_i196
#ISCELL
  pure_quanta_power universal_gnd *
  page476_i197
#ISCELL
  pure_quanta_power universal_gnd *
  page476_i198
#ISCELL
  pure_quanta_power universal_gnd *
  page476_i199
#CELL
  pure_quanta q_cap *
  page476_i202
#CELL
  pure_quanta q_capp *
  page476_i209
#CELL
  pure_quanta q_cap *
  page476_i21
#CELL
  pure_quanta q_cap *
  page476_i210
#ISCELL
  pure_quanta_power universal_gnd *
  page476_i211
#ISCELL
  pure_quanta_power universal_gnd *
  page476_i214
#ISCELL
  pure_quanta_power universal_gnd *
  page476_i215
#CELL
  pure_quanta q_cap *
  page476_i216
#CELL
  pure_quanta q_cap *
  page476_i217
#CELL
  pure_quanta q_res *
  page476_i220
#CELL
  pure_quanta q_res *
  page476_i221
#CELL
  pure_quanta q_capp *
  page476_i222
#CELL
  pure_quanta q_cap *
  page476_i223
#CELL
  pure_quanta q_capp *
  page476_i224
#CELL
  pure_quanta q_capp *
  page476_i225
#CELL
  pure_quanta q_capp *
  page476_i226
#CELL
  pure_quanta q_capp *
  page476_i227
#ISCELL
  pure_quanta_power vcc15 *
  page476_i23
#ISCELL
  pure_quanta_power vcc15 *
  page476_i230
#CELL
  pure_quanta q_capp *
  page476_i231
#CELL
  pure_quanta q_cap *
  page476_i232
#ISCELL
  pure_quanta_power vcc15 *
  page476_i233
#ISCELL
  pure_quanta_power universal_gnd *
  page476_i234
#CELL
  pure_quanta q_capp *
  page476_i236
#ISCELL
  pure_quanta_power universal_gnd *
  page476_i237
#CELL
  pure_quanta q_capp *
  page476_i238
#CELL
  pure_quanta q_capp *
  page476_i239
#CELL
  pure_quanta q_cap *
  page476_i24
#ISCELL
  pure_quanta_power universal_gnd *
  page476_i240
#CELL
  pure_quanta q_cap *
  page476_i241
#CELL
  pure_quanta q_cap *
  page476_i242
#CELL
  pure_quanta q_cap *
  page476_i243
#CELL
  pure_quanta q_cap *
  page476_i244
#CELL
  pure_quanta q_cap *
  page476_i245
#ISCELL
  pure_quanta_power universal_gnd *
  page476_i246
#CELL
  pure_quanta q_capp *
  page476_i247
#CELL
  pure_quanta q_capp *
  page476_i248
#ISCELL
  pure_quanta_power universal_gnd *
  page476_i249
#CELL
  pure_quanta q_cap *
  page476_i250
#CELL
  pure_quanta q_cap *
  page476_i251
#ISCELL
  pure_quanta_power universal_gnd *
  page476_i252
#CELL
  pure_quanta q_cap *
  page476_i253
#ISCELL
  pure_quanta_power universal_gnd *
  page476_i254
#CELL
  pure_quanta q_cap *
  page476_i255
#ISCELL
  pure_quanta_power universal_gnd *
  page476_i256
#CELL
  pure_quanta q_inductor *
  page476_i257
#CELL
  pure_quanta q_cap *
  page476_i258
#CELL
  pure_quanta q_cap *
  page476_i259
#ISCELL
  pure_quanta_power universal_gnd *
  page476_i260
#ISCELL
  pure_quanta_power universal_gnd *
  page476_i261
#CELL
  pure_quanta q_res *
  page476_i262
#CELL
  pure_quanta q_res *
  page476_i263
#ISCELL
  pure_quanta_power universal_gnd *
  page476_i264
#ISCELL
  pure_quanta_power universal_power *
  page476_i265
#CELL
  pure_quanta q_cap *
  page476_i267
#ISCELL
  pure_quanta_power universal_gnd *
  page476_i268
#CELL
  pure_quanta q_res *
  page476_i269
#CELL
  pure_quanta q_cap *
  page476_i27
#CELL
  pure_quanta isl99390frztr5935 *
  page476_i270
#CELL
  pure_quanta q_cap *
  page476_i271
#ISCELL
  pure_quanta_power universal_gnd *
  page476_i272
#ISCELL
  standard offpage *
  page476_i273
#ISCELL
  standard offpage *
  page476_i274
#ISCELL
  standard offpage *
  page476_i275
#CELL
  pure_quanta q_res *
  page476_i276
#ISCELL
  pure_quanta_power universal_gnd *
  page476_i277
#ISCELL
  standard offpage *
  page476_i280
#CELL
  pure_quanta q_cap *
  page476_i281
#ISCELL
  pure_quanta_power universal_gnd *
  page476_i282
#CELL
  pure_quanta q_res *
  page476_i283
#ISCELL
  pure_quanta_power universal_gnd *
  page476_i284
#CELL
  pure_quanta q_cap *
  page476_i285
#CELL
  pure_quanta q_res *
  page476_i286
#ISCELL
  pure_quanta_power universal_gnd *
  page476_i287
#CELL
  pure_quanta q_cap *
  page476_i288
#ISCELL
  pure_quanta_power universal_power *
  page476_i289
#CELL
  pure_quanta q_cap *
  page476_i29
#ISCELL
  pure_quanta_power universal_gnd *
  page476_i290
#CELL
  pure_quanta q_cap *
  page476_i291
#CELL
  pure_quanta q_cap *
  page476_i30
#CELL
  pure_quanta q_cap *
  page476_i33
#CELL
  pure_quanta q_inductor *
  page476_i34
#ISCELL
  pure_quanta_power universal_power *
  page476_i4
#CELL
  pure_quanta q_res *
  page476_i42
#CELL
  pure_quanta q_cap *
  page476_i47
#CELL
  pure_quanta q_cap *
  page476_i48
#CELL
  pure_quanta isl99390frztr5935 *
  page476_i53
#CELL
  pure_quanta q_res *
  page476_i58
#ISCELL
  standard offpage *
  page476_i59
#CELL
  pure_quanta q_cap *
  page476_i6
#ISCELL
  standard offpage *
  page476_i60
#ISCELL
  standard offpage *
  page476_i61
#ISCELL
  standard offpage *
  page476_i62
#CELL
  pure_quanta q_cap *
  page476_i68
